(kicad_pcb
	(version 20260206)
	(generator "pcbnew")
	(generator_version "10.0")
	(general
		(thickness 1.6)
		(legacy_teardrops no)
	)
	(paper "A4")
	(title_block
		(title "01162023_DA0F0TEBIF0_F0T_Expander_BD_F_brd_V02_OCP.brd")
		(comment 1 "Grand Teton / footprints 870-875 of 9728")
	)
	(layers
		(0 "F.Cu" signal "TOP")
		(4 "In1.Cu" signal "GND")
		(6 "In2.Cu" signal "VCC")
		(8 "In3.Cu" signal "VCC1")
		(10 "In4.Cu" signal "GND1")
		(12 "In5.Cu" signal "IN1")
		(14 "In6.Cu" signal "GND2")
		(16 "In7.Cu" signal "IN2")
		(18 "In8.Cu" signal "GND3")
		(20 "In9.Cu" signal "IN3")
		(22 "In10.Cu" signal "GND4")
		(24 "In11.Cu" signal "IN4")
		(26 "In12.Cu" signal "GND5")
		(28 "In13.Cu" signal "IN5")
		(30 "In14.Cu" signal "GND6")
		(32 "In15.Cu" signal "IN6")
		(34 "In16.Cu" signal "GND7")
		(2 "B.Cu" signal "BOTTOM")
		(9 "F.Adhes" user "F.Adhesive")
		(11 "B.Adhes" user "B.Adhesive")
		(13 "F.Paste" user "Package Geometry/Pastemask Top")
		(15 "B.Paste" user "Package Geometry/Pastemask Bottom")
		(5 "F.SilkS" user "Ref Des/Silkscreen Top")
		(7 "B.SilkS" user "Ref Des/Silkscreen Bottom")
		(1 "F.Mask" user "Board Geometry/Soldermask Top")
		(3 "B.Mask" user "Board Geometry/Soldermask Bottom")
		(17 "Dwgs.User" user "User.Drawings")
		(19 "Cmts.User" user "User.Comments")
		(21 "Eco1.User" user "User.Eco1")
		(23 "Eco2.User" user "User.Eco2")
		(25 "Edge.Cuts" user "Board Geometry/Outline")
		(27 "Margin" user)
		(31 "F.CrtYd" user "Package Geometry/Place Bound Top")
		(29 "B.CrtYd" user "Package Geometry/Place Bound Bottom")
		(35 "F.Fab" user "Ref Des/Assembly Top")
		(33 "B.Fab" user "Ref Des/Assembly Bottom")
	)
	(footprint ""
		(layer "F.Cu")
		(at 448.64528 -410.15666 90)
		(property "Reference" "U329"
			(at -1.245108 3.82016 90)
			(unlocked yes)
			(layer "F.SilkS")
			(effects
				(font
					(size 0.7874 0.5842)
					(thickness 0.1524)
				)
				(justify left)
			)
		)
		(property "Value" ""
			(at 0 0 90)
			(layer "F.Fab")
			(effects
				(font
					(size 1.27 1.27)
				)
			)
		)
		(duplicate_pad_numbers_are_jumpers no)
		(fp_line
			(start 3.447796 -2.500122)
			(end 1.484122 -2.500122)
			(stroke
				(width 0.1524)
				(type default)
			)
			(layer "F.SilkS")
		)
		(fp_line
			(start 1.484122 -2.500122)
			(end 0 -1.016)
			(stroke
				(width 0.1524)
				(type default)
			)
			(layer "F.SilkS")
		)
		(fp_line
			(start -1.484122 -2.500122)
			(end -3.447796 -2.500122)
			(stroke
				(width 0.1524)
				(type default)
			)
			(layer "F.SilkS")
		)
		(fp_line
			(start -3.447796 -2.500122)
			(end -3.447796 2.500122)
			(stroke
				(width 0.1524)
				(type default)
			)
			(layer "F.SilkS")
		)
		(fp_line
			(start 0 -1.016)
			(end -1.484122 -2.500122)
			(stroke
				(width 0.1524)
				(type default)
			)
			(layer "F.SilkS")
		)
		(fp_line
			(start 3.447796 2.500122)
			(end 3.447796 -2.500122)
			(stroke
				(width 0.1524)
				(type default)
			)
			(layer "F.SilkS")
		)
		(fp_line
			(start -3.447796 2.500122)
			(end 3.447796 2.500122)
			(stroke
				(width 0.1524)
				(type default)
			)
			(layer "F.SilkS")
		)
		(fp_poly
			(pts
				(xy -4.053332 -3.443732) (xy -4.771644 -2.72542) (xy -3.693922 -2.36601)
			)
			(stroke
				(width 0)
				(type default)
			)
			(fill yes)
			(layer "F.SilkS")
		)
		(fp_line
			(start 1.999996 -2.500122)
			(end -1.999996 -2.500122)
			(stroke
				(width 0.1)
				(type default)
			)
			(layer "F.Fab")
		)
		(fp_line
			(start -1.999996 -2.500122)
			(end -1.999996 2.500122)
			(stroke
				(width 0.1)
				(type default)
			)
			(layer "F.Fab")
		)
		(fp_line
			(start 1.999996 2.500122)
			(end 1.999996 -2.500122)
			(stroke
				(width 0.1)
				(type default)
			)
			(layer "F.Fab")
		)
		(fp_line
			(start -1.999996 2.500122)
			(end 1.999996 2.500122)
			(stroke
				(width 0.1)
				(type default)
			)
			(layer "F.Fab")
		)
		(fp_poly
			(pts
				(xy -4.5974 -2.413) (xy -4.5974 -1.397) (xy -3.5814 -1.905)
			)
			(stroke
				(width 0)
				(type default)
			)
			(fill yes)
			(layer "F.Fab")
		)
		(pad "1" smd rect
			(at -2.649982 -1.905)
			(size 0.6096 1.3208)
			(layers "F.Cu" "F.Mask" "F.Paste")
			(net "SMB_LM75_1_SDA")
		)
		(pad "2" smd rect
			(at -2.649982 -0.635)
			(size 0.6096 1.3208)
			(layers "F.Cu" "F.Mask" "F.Paste")
			(net "SMB_LM75_1_SCL")
		)
		(pad "3" smd rect
			(at -2.649982 0.635)
			(size 0.6096 1.3208)
			(layers "F.Cu" "F.Mask" "F.Paste")
			(net "Net_406")
		)
		(pad "4" smd rect
			(at -2.649982 1.905)
			(size 0.6096 1.3208)
			(layers "F.Cu" "F.Mask" "F.Paste")
			(net "GND")
		)
		(pad "5" smd rect
			(at 2.649982 1.905)
			(size 0.6096 1.3208)
			(layers "F.Cu" "F.Mask" "F.Paste")
			(net "LM75_1_A2")
		)
		(pad "6" smd rect
			(at 2.649982 0.635)
			(size 0.6096 1.3208)
			(layers "F.Cu" "F.Mask" "F.Paste")
			(net "LM75_1_A1")
		)
		(pad "7" smd rect
			(at 2.649982 -0.635)
			(size 0.6096 1.3208)
			(layers "F.Cu" "F.Mask" "F.Paste")
			(net "LM75_1_A0")
		)
		(pad "8" smd rect
			(at 2.649982 -1.905)
			(size 0.6096 1.3208)
			(layers "F.Cu" "F.Mask" "F.Paste")
			(net "P3V3_AUX")
		)
	)
	(footprint ""
		(layer "F.Cu")
		(at 320.354452 -218.309698 180)
		(property "Reference" "D19"
			(at 3.743452 -0.023368 0)
			(unlocked yes)
			(layer "F.SilkS")
			(effects
				(font
					(size 0.7874 0.5842)
					(thickness 0.1524)
				)
				(justify left)
			)
		)
		(property "Value" ""
			(at 0 0 180)
			(layer "F.Fab")
			(effects
				(font
					(size 1.27 1.27)
				)
			)
		)
		(duplicate_pad_numbers_are_jumpers no)
		(fp_line
			(start 1.16078 0.4826)
			(end -0.64008 0.4826)
			(stroke
				(width 0.1524)
				(type default)
			)
			(layer "F.SilkS")
		)
		(fp_line
			(start 1.16078 -0.4826)
			(end 1.16078 0.4826)
			(stroke
				(width 0.1524)
				(type default)
			)
			(layer "F.SilkS")
		)
		(fp_line
			(start 1.03378 0.4826)
			(end -0.79248 0.4826)
			(stroke
				(width 0.1524)
				(type default)
			)
			(layer "F.SilkS")
		)
		(fp_line
			(start 1.03378 -0.4826)
			(end 1.03378 0.4826)
			(stroke
				(width 0.1524)
				(type default)
			)
			(layer "F.SilkS")
		)
		(fp_line
			(start 0.90678 0.4826)
			(end -0.90678 0.4826)
			(stroke
				(width 0.1524)
				(type default)
			)
			(layer "F.SilkS")
		)
		(fp_line
			(start 0.90678 -0.4826)
			(end 0.90678 0.4826)
			(stroke
				(width 0.1524)
				(type default)
			)
			(layer "F.SilkS")
		)
		(fp_line
			(start -0.64008 -0.4826)
			(end 1.16078 -0.4826)
			(stroke
				(width 0.1524)
				(type default)
			)
			(layer "F.SilkS")
		)
		(fp_line
			(start -0.79248 -0.4826)
			(end 1.03378 -0.4826)
			(stroke
				(width 0.1524)
				(type default)
			)
			(layer "F.SilkS")
		)
		(fp_line
			(start -0.89408 -0.4826)
			(end 0.90678 -0.4826)
			(stroke
				(width 0.1524)
				(type default)
			)
			(layer "F.SilkS")
		)
		(fp_line
			(start -0.90678 0.4826)
			(end -0.90678 -0.4699)
			(stroke
				(width 0.1524)
				(type default)
			)
			(layer "F.SilkS")
		)
		(fp_line
			(start 0.499872 0.249936)
			(end -0.499872 0.249936)
			(stroke
				(width 0.1)
				(type default)
			)
			(layer "F.Fab")
		)
		(fp_line
			(start 0.499872 -0.249936)
			(end 0.499872 0.249936)
			(stroke
				(width 0.1)
				(type default)
			)
			(layer "F.Fab")
		)
		(fp_line
			(start -0.499872 0.249936)
			(end -0.499872 -0.249936)
			(stroke
				(width 0.1)
				(type default)
			)
			(layer "F.Fab")
		)
		(fp_line
			(start -0.499872 -0.249936)
			(end 0.499872 -0.249936)
			(stroke
				(width 0.1)
				(type default)
			)
			(layer "F.Fab")
		)
		(pad "A" smd rect
			(at -0.47498 0 180)
			(size 0.6096 0.7112)
			(layers "F.Cu" "F.Mask" "F.Paste")
			(net "LED_POSTCODE_R_6")
		)
		(pad "C" smd rect
			(at 0.47498 0 180)
			(size 0.6096 0.7112)
			(layers "F.Cu" "F.Mask" "F.Paste")
			(net "FPGA_DEBUG_LED_R_N")
		)
	)
	(footprint ""
		(layer "F.Cu")
		(at 370.889784 -235.756958)
		(property "Reference" "R6409"
			(at 0 0 0)
			(layer "F.SilkS")
			(hide yes)
			(effects
				(font
					(size 1.27 1.27)
				)
			)
		)
		(property "Value" ""
			(at 0 0 0)
			(layer "F.Fab")
			(effects
				(font
					(size 1.27 1.27)
				)
			)
		)
		(duplicate_pad_numbers_are_jumpers no)
		(fp_line
			(start -0.7874 -0.4064)
			(end 0.7874 -0.4064)
			(stroke
				(width 0.1524)
				(type default)
			)
			(layer "F.SilkS")
		)
		(fp_line
			(start -0.7874 0.4064)
			(end -0.7874 -0.4064)
			(stroke
				(width 0.1524)
				(type default)
			)
			(layer "F.SilkS")
		)
		(fp_line
			(start 0.7874 -0.4064)
			(end 0.7874 0.4064)
			(stroke
				(width 0.1524)
				(type default)
			)
			(layer "F.SilkS")
		)
		(fp_line
			(start 0.7874 0.4064)
			(end -0.7874 0.4064)
			(stroke
				(width 0.1524)
				(type default)
			)
			(layer "F.SilkS")
		)
		(fp_line
			(start -0.67945 -0.305054)
			(end -0.12065 -0.305054)
			(stroke
				(width 0.1)
				(type default)
			)
			(layer "F.Fab")
		)
		(fp_line
			(start -0.67945 0.3048)
			(end -0.67945 -0.305054)
			(stroke
				(width 0.1)
				(type default)
			)
			(layer "F.Fab")
		)
		(fp_line
			(start -0.12065 -0.305054)
			(end -0.12065 -0.2794)
			(stroke
				(width 0.1)
				(type default)
			)
			(layer "F.Fab")
		)
		(fp_line
			(start -0.12065 -0.2794)
			(end 0.12065 -0.2794)
			(stroke
				(width 0.1)
				(type default)
			)
			(layer "F.Fab")
		)
		(fp_line
			(start -0.12065 0.2794)
			(end -0.12065 0.3048)
			(stroke
				(width 0.1)
				(type default)
			)
			(layer "F.Fab")
		)
		(fp_line
			(start -0.12065 0.3048)
			(end -0.67945 0.3048)
			(stroke
				(width 0.1)
				(type default)
			)
			(layer "F.Fab")
		)
		(fp_line
			(start 0.120396 0.2794)
			(end -0.12065 0.2794)
			(stroke
				(width 0.1)
				(type default)
			)
			(layer "F.Fab")
		)
		(fp_line
			(start 0.120396 0.3048)
			(end 0.120396 0.2794)
			(stroke
				(width 0.1)
				(type default)
			)
			(layer "F.Fab")
		)
		(fp_line
			(start 0.12065 -0.3048)
			(end 0.67945 -0.3048)
			(stroke
				(width 0.1)
				(type default)
			)
			(layer "F.Fab")
		)
		(fp_line
			(start 0.12065 -0.2794)
			(end 0.12065 -0.3048)
			(stroke
				(width 0.1)
				(type default)
			)
			(layer "F.Fab")
		)
		(fp_line
			(start 0.67945 -0.3048)
			(end 0.67945 0.3048)
			(stroke
				(width 0.1)
				(type default)
			)
			(layer "F.Fab")
		)
		(fp_line
			(start 0.67945 0.3048)
			(end 0.120396 0.3048)
			(stroke
				(width 0.1)
				(type default)
			)
			(layer "F.Fab")
		)
		(pad "1" smd circle
			(at -0.40005 0)
			(size 0 0)
			(layers "F.Cu" "F.Mask" "F.Paste")
			(net "GND")
		)
		(pad "2" smd circle
			(at 0.40005 0)
			(size 0 0)
			(layers "F.Cu" "F.Mask" "F.Paste")
			(net "PWRGD_P5V_AUX_BUF")
		)
	)
	(footprint ""
		(layer "F.Cu")
		(at 221.251272 -146.990562)
		(property "Reference" "R4204"
			(at 0 0 0)
			(layer "F.SilkS")
			(hide yes)
			(effects
				(font
					(size 1.27 1.27)
				)
			)
		)
		(property "Value" ""
			(at 0 0 0)
			(layer "F.Fab")
			(effects
				(font
					(size 1.27 1.27)
				)
			)
		)
		(duplicate_pad_numbers_are_jumpers no)
		(fp_line
			(start -0.7874 -0.4064)
			(end 0.7874 -0.4064)
			(stroke
				(width 0.1524)
				(type default)
			)
			(layer "F.SilkS")
		)
		(fp_line
			(start -0.7874 0.4064)
			(end -0.7874 -0.4064)
			(stroke
				(width 0.1524)
				(type default)
			)
			(layer "F.SilkS")
		)
		(fp_line
			(start 0.7874 -0.4064)
			(end 0.7874 0.4064)
			(stroke
				(width 0.1524)
				(type default)
			)
			(layer "F.SilkS")
		)
		(fp_line
			(start 0.7874 0.4064)
			(end -0.7874 0.4064)
			(stroke
				(width 0.1524)
				(type default)
			)
			(layer "F.SilkS")
		)
		(fp_line
			(start -0.67945 -0.305054)
			(end -0.12065 -0.305054)
			(stroke
				(width 0.1)
				(type default)
			)
			(layer "F.Fab")
		)
		(fp_line
			(start -0.67945 0.3048)
			(end -0.67945 -0.305054)
			(stroke
				(width 0.1)
				(type default)
			)
			(layer "F.Fab")
		)
		(fp_line
			(start -0.12065 -0.305054)
			(end -0.12065 -0.2794)
			(stroke
				(width 0.1)
				(type default)
			)
			(layer "F.Fab")
		)
		(fp_line
			(start -0.12065 -0.2794)
			(end 0.12065 -0.2794)
			(stroke
				(width 0.1)
				(type default)
			)
			(layer "F.Fab")
		)
		(fp_line
			(start -0.12065 0.2794)
			(end -0.12065 0.3048)
			(stroke
				(width 0.1)
				(type default)
			)
			(layer "F.Fab")
		)
		(fp_line
			(start -0.12065 0.3048)
			(end -0.67945 0.3048)
			(stroke
				(width 0.1)
				(type default)
			)
			(layer "F.Fab")
		)
		(fp_line
			(start 0.120396 0.2794)
			(end -0.12065 0.2794)
			(stroke
				(width 0.1)
				(type default)
			)
			(layer "F.Fab")
		)
		(fp_line
			(start 0.120396 0.3048)
			(end 0.120396 0.2794)
			(stroke
				(width 0.1)
				(type default)
			)
			(layer "F.Fab")
		)
		(fp_line
			(start 0.12065 -0.3048)
			(end 0.67945 -0.3048)
			(stroke
				(width 0.1)
				(type default)
			)
			(layer "F.Fab")
		)
		(fp_line
			(start 0.12065 -0.2794)
			(end 0.12065 -0.3048)
			(stroke
				(width 0.1)
				(type default)
			)
			(layer "F.Fab")
		)
		(fp_line
			(start 0.67945 -0.3048)
			(end 0.67945 0.3048)
			(stroke
				(width 0.1)
				(type default)
			)
			(layer "F.Fab")
		)
		(fp_line
			(start 0.67945 0.3048)
			(end 0.120396 0.3048)
			(stroke
				(width 0.1)
				(type default)
			)
			(layer "F.Fab")
		)
		(pad "1" smd circle
			(at -0.40005 0)
			(size 0 0)
			(layers "F.Cu" "F.Mask" "F.Paste")
			(net "GND")
		)
		(pad "2" smd circle
			(at 0.40005 0)
			(size 0 0)
			(layers "F.Cu" "F.Mask" "F.Paste")
			(net "PU_CK440_PEX_SHFT_LD_N")
		)
	)
	(footprint ""
		(layer "F.Cu")
		(at 129.86639 -184.656984 -90)
		(property "Reference" "R1117"
			(at 0 0 270)
			(layer "F.SilkS")
			(hide yes)
			(effects
				(font
					(size 1.27 1.27)
				)
			)
		)
		(property "Value" ""
			(at 0 0 270)
			(layer "F.Fab")
			(effects
				(font
					(size 1.27 1.27)
				)
			)
		)
		(duplicate_pad_numbers_are_jumpers no)
		(fp_line
			(start 0.7874 0.4064)
			(end -0.7874 0.4064)
			(stroke
				(width 0.1524)
				(type default)
			)
			(layer "F.SilkS")
		)
		(fp_line
			(start -0.67945 0.3048)
			(end -0.67945 -0.305054)
			(stroke
				(width 0.1)
				(type default)
			)
			(layer "F.Fab")
		)
		(fp_line
			(start -0.12065 0.3048)
			(end -0.67945 0.3048)
			(stroke
				(width 0.1)
				(type default)
			)
			(layer "F.Fab")
		)
		(fp_line
			(start 0.120396 0.3048)
			(end 0.120396 0.2794)
			(stroke
				(width 0.1)
				(type default)
			)
			(layer "F.Fab")
		)
		(fp_line
			(start 0.67945 0.3048)
			(end 0.120396 0.3048)
			(stroke
				(width 0.1)
				(type default)
			)
			(layer "F.Fab")
		)
		(fp_line
			(start -0.12065 0.2794)
			(end -0.12065 0.3048)
			(stroke
				(width 0.1)
				(type default)
			)
			(layer "F.Fab")
		)
		(fp_line
			(start 0.120396 0.2794)
			(end -0.12065 0.2794)
			(stroke
				(width 0.1)
				(type default)
			)
			(layer "F.Fab")
		)
		(fp_line
			(start -0.12065 -0.2794)
			(end 0.12065 -0.2794)
			(stroke
				(width 0.1)
				(type default)
			)
			(layer "F.Fab")
		)
		(fp_line
			(start 0.12065 -0.2794)
			(end 0.12065 -0.3048)
			(stroke
				(width 0.1)
				(type default)
			)
			(layer "F.Fab")
		)
		(fp_line
			(start 0.12065 -0.3048)
			(end 0.67945 -0.3048)
			(stroke
				(width 0.1)
				(type default)
			)
			(layer "F.Fab")
		)
		(fp_line
			(start 0.67945 -0.3048)
			(end 0.67945 0.3048)
			(stroke
				(width 0.1)
				(type default)
			)
			(layer "F.Fab")
		)
		(fp_line
			(start -0.67945 -0.305054)
			(end -0.12065 -0.305054)
			(stroke
				(width 0.1)
				(type default)
			)
			(layer "F.Fab")
		)
		(fp_line
			(start -0.12065 -0.305054)
			(end -0.12065 -0.2794)
			(stroke
				(width 0.1)
				(type default)
			)
			(layer "F.Fab")
		)
		(pad "1" smd circle
			(at -0.40005 0 270)
			(size 0 0)
			(layers "F.Cu" "F.Mask" "F.Paste")
			(net "CLK_100M_DB2000QL_GPU_REF2_R_DN")
		)
		(pad "2" smd circle
			(at 0.40005 0 270)
			(size 0 0)
			(layers "F.Cu" "F.Mask" "F.Paste")
			(net "CLK_100M_DB2000QL_GPU_REF2_DN")
		)
	)
	(footprint ""
		(layer "F.Cu")
		(at 332.956662 -10.545572 90)
		(property "Reference" "R1705"
			(at 0 0 90)
			(layer "F.SilkS")
			(hide yes)
			(effects
				(font
					(size 1.27 1.27)
				)
			)
		)
		(property "Value" ""
			(at 0 0 90)
			(layer "F.Fab")
			(effects
				(font
					(size 1.27 1.27)
				)
			)
		)
		(duplicate_pad_numbers_are_jumpers no)
		(fp_line
			(start 0.7874 -0.4064)
			(end 0.7874 0.4064)
			(stroke
				(width 0.1524)
				(type default)
			)
			(layer "F.SilkS")
		)
		(fp_line
			(start -0.7874 -0.4064)
			(end 0.7874 -0.4064)
			(stroke
				(width 0.1524)
				(type default)
			)
			(layer "F.SilkS")
		)
		(fp_line
			(start 0.7874 0.4064)
			(end -0.7874 0.4064)
			(stroke
				(width 0.1524)
				(type default)
			)
			(layer "F.SilkS")
		)
		(fp_line
			(start -0.7874 0.4064)
			(end -0.7874 -0.4064)
			(stroke
				(width 0.1524)
				(type default)
			)
			(layer "F.SilkS")
		)
		(fp_line
			(start -0.12065 -0.305054)
			(end -0.12065 -0.2794)
			(stroke
				(width 0.1)
				(type default)
			)
			(layer "F.Fab")
		)
		(fp_line
			(start -0.67945 -0.305054)
			(end -0.12065 -0.305054)
			(stroke
				(width 0.1)
				(type default)
			)
			(layer "F.Fab")
		)
		(fp_line
			(start 0.67945 -0.3048)
			(end 0.67945 0.3048)
			(stroke
				(width 0.1)
				(type default)
			)
			(layer "F.Fab")
		)
		(fp_line
			(start 0.12065 -0.3048)
			(end 0.67945 -0.3048)
			(stroke
				(width 0.1)
				(type default)
			)
			(layer "F.Fab")
		)
		(fp_line
			(start 0.12065 -0.2794)
			(end 0.12065 -0.3048)
			(stroke
				(width 0.1)
				(type default)
			)
			(layer "F.Fab")
		)
		(fp_line
			(start -0.12065 -0.2794)
			(end 0.12065 -0.2794)
			(stroke
				(width 0.1)
				(type default)
			)
			(layer "F.Fab")
		)
		(fp_line
			(start 0.120396 0.2794)
			(end -0.12065 0.2794)
			(stroke
				(width 0.1)
				(type default)
			)
			(layer "F.Fab")
		)
		(fp_line
			(start -0.12065 0.2794)
			(end -0.12065 0.3048)
			(stroke
				(width 0.1)
				(type default)
			)
			(layer "F.Fab")
		)
		(fp_line
			(start 0.67945 0.3048)
			(end 0.120396 0.3048)
			(stroke
				(width 0.1)
				(type default)
			)
			(layer "F.Fab")
		)
		(fp_line
			(start 0.120396 0.3048)
			(end 0.120396 0.2794)
			(stroke
				(width 0.1)
				(type default)
			)
			(layer "F.Fab")
		)
		(fp_line
			(start -0.12065 0.3048)
			(end -0.67945 0.3048)
			(stroke
				(width 0.1)
				(type default)
			)
			(layer "F.Fab")
		)
		(fp_line
			(start -0.67945 0.3048)
			(end -0.67945 -0.305054)
			(stroke
				(width 0.1)
				(type default)
			)
			(layer "F.Fab")
		)
		(pad "1" smd circle
			(at -0.40005 0 90)
			(size 0 0)
			(layers "F.Cu" "F.Mask" "F.Paste")
			(net "P3V3_SSD11")
		)
		(pad "2" smd circle
			(at 0.40005 0 90)
			(size 0 0)
			(layers "F.Cu" "F.Mask" "F.Paste")
			(net "SMB_ISO_SSD11_SCL")
		)
	)
)
